FILE_TYPE = CONNECTIVITY;
{Allegro Design Entry HDL 16.6-p007 (v16-6-112F) 10/10/2012}
"PAGE_NUMBER" = 212;
0"NC";
1"GND\g";
2"GND\g";
3"GND\g";
4"GND\g";
5"GND\g";
6"PVCCIO_CPU0\g";
7"GND\g";
8"GND\g";
9"GND\g";
10"GND\g";
11"GND\g";
12"P12V_STBY\g";
13"P5V_STBY\g";
14"GND\g";
15"PVCCIO_CPU0\g";
16"VR_FET_SW_P12V_STBY_PVCCIO_CPU0\g";
17"VR_FET_SW_P12V_STBY_PVCCIO_CPU0\g"VOLTAGE"12";
18"PVCCIO_CPU0\g";
19"VR_PVCCIO_CPU0_PH1_VCIN"VOLTAGE"5";
20"VR_PVCCIO_CPU0_PH1_BOOT_R";
21"VR_PVCCIO_CPU0_PH1_BOOT";
22"VSENSE_PVCCIO_CPU0_SKT_VRTN";
23"VSENSE_PVCCIO_CPU0_SKT_VSEN";
24"VR_PVCCIO_CPU0_PH1_PHASE"VOLTAGE"5";
25"VSENSE_PVCCIO_CPU0_AVSN";
26"VSENSE_PVCCIO_CPU0_AVSP";
27"VR_PVCCIO_CPU0_PWM1";
28"TP_PVCCIO_CPU0_GL_0";
29"TP_PVCCIO_CPU0_GL_1";
30"ISENSE_PVCCIO_CPU0_PH1_IMON";
31"NC_PVCCIO_CPU0_PH1_P31";
32"VR_PVCCIO_CPU0_OCSET";
33"VR_PVCCIO_CPU0_AIREF1";
34"A_TSENSE_PVCCIO_CPU0";
35"VR_PVCCIO_CPU0_PH1_SW"VOLTAGE"5";
36"UN$212$3D01R5F-GP$I112$2";
%"IR354XX"
"1","(825,3775)","0","mstr_discrete","I101";
;
PACK_TYPE"SM"
$SEC"1"
CDS_SEC"1"
CDS_LOCATION"EU7C1"
CDS_LIB"mstr_discrete"
VALUE"IR35412"
LOCATION"EU7C1"
NO_XNET_CONNECTION"1"
MATERIAL"IC"
PART_NUMBER"H73684-001";
"TOUT_FLT"
$PN"36"34;
"NC"
$PN"31"31;
"OCSET"
$PN"37"32;
"IOUT"
$PN"38"30;
"SW"
$PN"10"35;
"BOOST"
$PN"33"20;
"REFIN"
$PN"39"33;
"PWM"
$PN"34"27;
"PHASE"
$PN"32"24;
"VIN<0>"
$PN"25"16;
"VCC"
$PN"3"19;
"VIN<1>"
$PN"30"16;
"EN"
$PN"35"13;
"VDRV"
$PN"4"13;
"VOS"
$PN"1"6;
"LGND"
$PN"2"8;
"PGND<1>"
$PN"7"8;
"PGND<2>"
$PN"40"8;
"PGND<0>"
$PN"5"8;
"GL<0>"
$PN"6"28;
"GL<1>"
$PN"41"29;
%"GND"
"1","(3100,3700)","0","mstr_symbols","I102";
;
HDL_POWER"GND"
BODY_TYPE"PLUMBING"
VOLTAGE"0"
CDS_LIB"mstr_symbols"
SIZE"1B"
BOM_COST"PROC_VRD_VCCIN_CPU0"
ROOM"PVSA_CPU1_PWR_VR";
"A\NAC"1;
%"RES"
"2","(3100,3950)","0","mstr_discrete","I103";
;
CDS_LOCATION"R7C25"
$SEC"1"
CDS_SEC"1"
CDS_LIB"mstr_discrete"
PACK_TYPE"0402"
LOCATION"R7C25"
MATERIAL"EMPTY"
VALUE"68.1K"
TOLERANCE"1%"
WATTAGE"1/16W"
PART_NUMBER"G21796-187";
"A"
$PN"1"32;
"B"
$PN"2"1;
%"SHUNT"
"1","(-1300,1850)","0","mstr_misc","I104";
;
CDS_SEC"1"
CDS_LOCATION"SH3P1"
SEC_TYPE"SH0201"
SEC"1"
CDS_LIB"mstr_misc"
PIN_SHORT"A:B"
PACK_TYPE"SH0201"
MATERIAL"EMPTY"
LOCATION"SH3P1"
PART_NUMBER"N_A";
"A"
$PN"1"23;
"B"
$PN"2"26;
%"SHUNT"
"1","(-1300,1400)","0","mstr_misc","I105";
;
CDS_SEC"1"
CDS_LOCATION"SH3P2"
SEC_TYPE"SH0201"
SEC"1"
CDS_LIB"mstr_misc"
MATERIAL"EMPTY"
PACK_TYPE"SH0201"
PIN_SHORT"A:B"
PART_NUMBER"N_A"
LOCATION"SH3P2";
"A"
$PN"1"22;
"B"
$PN"2"25;
%"CAP_A"
"1","(25,3275)","0","dev_discrete","I106";
;
CDS_SEC"1"
$SEC"1"
CDS_LOCATION"CT70"
CDS_LIB"dev_discrete"
ROOM"PVCCIN_CPU0_PWR_VR"
MATERIAL"X7R"
LOCATION"CT70"
VOLTAGE"16V"
TOLERANCE"10%"
PART_NUMBER"A36096-030"
PACK_TYPE"0402V"
VALUE"0.1UF"
STATUS"NOPOP";
"B"
$PN"2"2;
"A"
$PN"1"33;
%"GND"
"1","(25,3025)","0","mstr_symbols","I107";
;
HDL_POWER"GND"
BODY_TYPE"PLUMBING"
CDS_LIB"mstr_symbols"
VOLTAGE"0"
SIZE"1B"
BOM_COST"PROC_VRD_VCCIN_CPU0"
ROOM"PVCCIN_CPU0_PWR_VR";
"A\NAC"2;
%"CAP"
"1","(1950,3800)","0","mstr_discrete","I109";
;
CDS_SEC"1"
$SEC"1"
CDS_LOCATION"CT71"
CDS_LIB"mstr_discrete"
ROOM"VDDQ_KLM_PWR_VR"
MATERIAL"X7R"
TOLERANCE"10%"
PACK_TYPE"0402LF"
STATUS"NOPOP"
VALUE"1000PF"
VOLTAGE"50V"
LOCATION"CT71"
PART_NUMBER"A36096-046";
"A"
$PN"1"34;
"B"
$PN"2"3;
%"GND"
"1","(1950,3575)","0","mstr_symbols","I110";
;
HDL_POWER"GND"
BODY_TYPE"PLUMBING"
CDS_LIB"mstr_symbols"
SIZE"1B"
VOLTAGE"0"
ROOM"VDDQ_KLM_PWR_VR";
"A\NAC"3;
%"SC2K2P50V3KX-GP"
"1","(2050,3325)","0","w_hdl","I111";
;
CDS_SEC"1"
$SEC"1"
CDS_LOCATION"CT72"
CDS_LIB"w_hdl"
CDS_LMAN_SYM_OUTLINE"-50,25,50,-25"
PART_NUMBER"78.22224.2BL"
PACK_TYPE"SMD-BCG6"
LOCATION"CT72"
STATUS"NOPOP"
VALUE"SC2K2P50V3KX-GP";
"2"
$PN"2"36;
"1"
$PN"1"35;
%"3D01R5F-GP"
"1","(2050,3000)","4","w_hdl","I112";
;
CDS_SEC"1"
$SEC"1"
CDS_LOCATION"RT48"
PACK_TYPE"SMD-RG5"
PART_NUMBER"64.3R015.16L"
CDS_LIB"w_hdl"
CDS_LMAN_SYM_OUTLINE"-50,75,50,-75"
STATUS"NOPOP"
LOCATION"RT48"
VALUE"3D01R5F-GP";
"2"
$PN"2"36;
"1"
$PN"1"4;
%"GND"
"1","(2050,2750)","0","mstr_symbols","I113";
;
HDL_POWER"GND"
BODY_TYPE"PLUMBING"
CDS_LIB"mstr_symbols"
SIZE"1B"
VOLTAGE"0"
BOM_COST"PROC_VRD_VCCIN_CPU0"
ROOM"PVCCIN_CPU0_PWR_VR";
"A\NAC"4;
%"RES"
"1","(-950,3575)","0","mstr_discrete","I114";
;
CDS_SEC"1"
$SEC"1"
CDS_LOCATION"RT47"
CDS_LIB"mstr_discrete"
ROOM"BMC_DEBUG_HEADER"
BOM_COST"DEBUG"
VALUE"0.0"
TOLERANCE"5%"
MATERIAL"CHIP"
WATTAGE"1/16W"
LOCATION"RT47"
PART_NUMBER"G21497-005"
PACK_TYPE"0402";
"B"
$PN"2"20;
"A"
$PN"1"21;
%"GND"
"1","(3375,2050)","0","mstr_symbols","I13";
;
HDL_POWER"GND"
BODY_TYPE"PLUMBING"
CDS_LIB"mstr_symbols"
VOLTAGE"0"
ROOM"PVCCIO_CPU0"
BOM_COST"PROC_VRD_PVCCIO_CPU0"
SIZE"1B";
"A\NAC"5;
%"CAPP"
"1","(3375,2400)","2","mstr_discrete","I16";
;
$SEC"1"
CDS_SEC"1"
ROOM"PVCCIO_CPU0"
BOM_COST"PROC_VRD_PVCCIO_CPU0"
CDS_LIB"mstr_discrete"
CDS_LOCATION"C3N38"
PACK_TYPE"3018"
MATERIAL"ALUM"
VOLTAGE"2.5V"
TOLERANCE"20%"
VALUE"470UF"
LOCATION"C3N38"
PART_NUMBER"699013-049";
"B"
$PN"2"5;
"A"
$PN"1"18;
%"CAPP"
"1","(2950,2400)","2","mstr_discrete","I17";
;
$SEC"1"
CDS_SEC"1"
ROOM"PVCCIO_CPU0"
BOM_COST"PROC_VRD_PVCCIO_CPU0"
CDS_LIB"mstr_discrete"
CDS_LOCATION"C3N26"
MATERIAL"ALUM"
PART_NUMBER"699013-049"
VALUE"470UF"
TOLERANCE"20%"
PACK_TYPE"3018"
VOLTAGE"2.5V"
LOCATION"C3N26";
"B"
$PN"2"5;
"A"
$PN"1"18;
%"CAPP"
"1","(2550,2400)","2","mstr_discrete","I18";
;
$SEC"1"
CDS_SEC"1"
ROOM"PVCCIO_CPU0"
BOM_COST"PROC_VRD_PVCCIO_CPU0"
CDS_LOCATION"C3N35"
CDS_LIB"mstr_discrete"
VALUE"470UF"
PART_NUMBER"699013-049"
LOCATION"C3N35"
VOLTAGE"2.5V"
TOLERANCE"20%"
MATERIAL"ALUM"
PACK_TYPE"3018";
"B"
$PN"2"5;
"A"
$PN"1"18;
%"PVCCIO_CPU0"
"1","(3600,3600)","0","mstr_symbols","I22";
;
HDL_POWER"PVCCIO_CPU0"
BODY_TYPE"PLUMBING"
CDS_LIB"mstr_symbols"
VOLTAGE"1.1V";
"G\NAC"6;
%"CAP_A"
"1","(2925,3275)","0","dev_discrete","I23";
;
CDS_LOCATION"C7C6"
BOM_COST"PROC_VRD_PVCCIO_CPU0"
CDS_SEC"1"
SEC_TYPE"0603V"
SEC"1"
ROOM"PVCCIO_CPU0"
CDS_LIB"dev_discrete"
PART_NUMBER"E15431-004"
VALUE"22.0UF"
PACK_TYPE"0603V"
TOLERANCE"20%"
VOLTAGE"4V"
MATERIAL"X6S"
LOCATION"C7C6";
"B"
$PN"2"7;
"A"
$PN"1"6;
%"GND"
"1","(2925,2950)","0","mstr_symbols","I24";
;
HDL_POWER"GND"
BODY_TYPE"PLUMBING"
ROOM"PVCCIO_CPU0"
BOM_COST"PROC_VRD_PVCCIO_CPU0"
SIZE"1B"
CDS_LIB"mstr_symbols"
VOLTAGE"0.0V";
"A\NAC"7;
%"INDUCTOR"
"1","(2475,3475)","0","mstr_discrete","I25";
;
$SEC"1"
CDS_SEC"1"
ROOM"PVCCIO_CPU0"
CDS_LIB"mstr_discrete"
CDS_LOCATION"L7C2"
MATERIAL"IND"
PACK_TYPE"SM"
VALUE"150NH"
LOCATION"L7C2"
PART_NUMBER"D92183-021";
"INA\NAC"
$PN"1"35;
"INB\NAC"
$PN"2"6;
%"GND"
"1","(1475,3025)","0","mstr_symbols","I29";
;
HDL_POWER"GND"
BODY_TYPE"PLUMBING"
BOM_COST"PROC_VRD_PVCCIO_CPU0"
CDS_LIB"mstr_symbols"
SIZE"1B"
VOLTAGE"0.0V"
ROOM"PVCCIO_CPU0";
"A\NAC"8;
%"RES"
"1","(-1725,4575)","0","mstr_discrete","I32";
;
CDS_SEC"1"
ROOM"PVCCIO_CPU0"
CDS_LOCATION"R3N7"
SEC"1"
SEC_TYPE"0402"
CDS_LIB"mstr_discrete"
VALUE"1.0"
MATERIAL"CHIP"
LOCATION"R3N7"
TOLERANCE"1%"
PACK_TYPE"0402"
PART_NUMBER"G21796-090"
WATTAGE"1/16W";
"B"
$PN"2"13;
"A"
$PN"1"19;
%"CAP"
"1","(-1275,4050)","0","mstr_discrete","I33";
;
CDS_SEC"1"
SEC_TYPE"0402"
SEC"1"
CDS_LOCATION"C7C18"
ROOM"PVCCIO_CPU0"
CDS_LIB"mstr_discrete"
VALUE"0.22UF"
LOCATION"C7C18"
VOLTAGE"16V"
PACK_TYPE"0402"
TOLERANCE"10%"
PART_NUMBER"A36096-155"
MATERIAL"X7R";
"A"
$PN"1"13;
"B"
$PN"2"9;
%"CAP_A"
"1","(-1425,4050)","2","dev_discrete","I34";
;
CDS_LOCATION"C7C20"
ROOM"PVCCIO_CPU0"
SEC"1"
SEC_TYPE"0402V"
CDS_SEC"1"
CDS_LIB"dev_discrete"
LOCATION"C7C20"
VALUE"1.0UF"
TOLERANCE"10%"
VOLTAGE"6.3V"
MATERIAL"X6S"
PACK_TYPE"0402V"
PART_NUMBER"D97712-004";
"B"
$PN"2"9;
"A"
$PN"1"13;
%"CAP"
"1","(-1975,4000)","0","mstr_discrete","I36";
;
CDS_SEC"1"
SEC_TYPE"0402"
SEC"1"
ROOM"PVCCIO_CPU0"
CDS_LOCATION"C7C17"
CDS_LIB"mstr_discrete"
LOCATION"C7C17"
VALUE"1.0UF"
MATERIAL"X6S"
VOLTAGE"16V"
TOLERANCE"10%"
PACK_TYPE"0402"
PART_NUMBER"D97712-011";
"A"
$PN"1"19;
"B"
$PN"2"9;
%"CAP"
"1","(-2025,3425)","2","mstr_discrete","I37";
;
CDS_SEC"1"
CDS_LIB"mstr_discrete"
CDS_LOCATION"C7C14"
ROOM"PVCCIO_CPU0"
SPOF"TRUE"
SEC_TYPE"0402"
SEC"1"
LOCATION"C7C14"
PACK_TYPE"0402"
MATERIAL"X7R"
VALUE"0.220UF"
VOLTAGE"16V"
TOLERANCE"10%"
PART_NUMBER"A36096-104";
"A"
$PN"1"21;
"B"
$PN"2"24;
%"CAP_A"
"1","(-2200,4000)","0","dev_discrete","I38";
;
CDS_LOCATION"C7C11"
CDS_SEC"1"
SEC_TYPE"0402V"
SEC"1"
ROOM"PVCCIO_CPU0"
CDS_LIB"dev_discrete"
PACK_TYPE"0402V"
PART_NUMBER"A36096-030"
MATERIAL"X7R"
TOLERANCE"10%"
VOLTAGE"16V"
VALUE"0.1UF"
LOCATION"C7C11";
"B"
$PN"2"9;
"A"
$PN"1"16;
%"CAP"
"1","(-2450,4025)","0","mstr_discrete","I39";
;
CDS_SEC"1"
ROOM"PVCCIO_CPU0"
CDS_LOCATION"C7C12"
SEC"1"
SEC_TYPE"0402"
CDS_LIB"mstr_discrete"
LOCATION"C7C12"
VALUE"1.0UF"
PART_NUMBER"D97712-011"
PACK_TYPE"0402"
TOLERANCE"10%"
VOLTAGE"16V"
MATERIAL"X6S";
"A"
$PN"1"16;
"B"
$PN"2"9;
%"CAP"
"1","(-2675,4000)","0","mstr_discrete","I40";
;
CDS_SEC"1"
ROOM"PVCCIO_CPU0"
CDS_LOCATION"C3N36"
SEC"1"
SEC_TYPE"0805"
CDS_LIB"mstr_discrete"
LOCATION"C3N36"
PART_NUMBER"C95333-007"
VALUE"10UF"
TOLERANCE"10%"
PACK_TYPE"0805"
VOLTAGE"16V"
MATERIAL"X6S";
"A"
$PN"1"16;
"B"
$PN"2"9;
%"CAP"
"1","(-2900,4050)","0","mstr_discrete","I41";
;
CDS_SEC"1"
ROOM"PVCCIO_CPU0"
SEC"1"
SEC_TYPE"0805"
CDS_LOCATION"C3N33"
CDS_LIB"mstr_discrete"
LOCATION"C3N33"
VALUE"10UF"
PART_NUMBER"C95333-007"
TOLERANCE"10%"
PACK_TYPE"0805"
VOLTAGE"16V"
MATERIAL"X6S";
"A"
$PN"1"16;
"B"
$PN"2"9;
%"CAP"
"1","(-3150,4050)","0","mstr_discrete","I43";
;
CDS_SEC"1"
SEC_TYPE"0805"
SEC"1"
ROOM"PVCCIO_CPU0"
CDS_LOCATION"C3N34"
CDS_LIB"mstr_discrete"
LOCATION"C3N34"
VALUE"10UF"
PART_NUMBER"C95333-007"
TOLERANCE"10%"
PACK_TYPE"0805"
VOLTAGE"16V"
MATERIAL"X6S";
"A"
$PN"1"16;
"B"
$PN"2"9;
%"GND"
"1","(-3150,3675)","0","mstr_symbols","I44";
;
HDL_POWER"GND"
BODY_TYPE"PLUMBING"
SIZE"1B"
CDS_LIB"mstr_symbols"
VOLTAGE"0.0V"
BOM_COST"PROC_VRD_PVCCIO_CPU0"
ROOM"PVCCIO_CPU0";
"A\NAC"9;
%"CAP"
"1","(1400,2225)","2","mstr_discrete","I51";
;
CDS_SEC"1"
ROOM"PVCCIO_CPU1"
BOM_COST"PROC_VRD_VCCIO_CPU1"
SEC_TYPE"1210"
SEC"1"
CDS_LOCATION"C7C8"
CDS_LIB"mstr_discrete"
VALUE"100UF"
TOLERANCE"20%"
PACK_TYPE"1210"
VOLTAGE"16V"
MATERIAL"X5R"
LOCATION"C7C8"
PART_NUMBER"644066-127";
"A"
$PN"1"17;
"B"
$PN"2"10;
%"GND"
"1","(1400,1975)","0","mstr_symbols","I52";
;
HDL_POWER"GND"
BODY_TYPE"PLUMBING"
VOLTAGE"0.0V"
CDS_LIB"mstr_symbols"
SIZE"1B"
ROOM"PVCCIO_CPU1"
BOM_COST"MEM_VRD_PVCCIO_CPU1";
"A\NAC"10;
%"CAP"
"1","(825,2200)","0","mstr_discrete","I54";
;
CDS_SEC"1"
SEC"1"
SEC_TYPE"1210"
ROOM"PVCCIO_CPU1"
BOM_COST"PROC_VRD_VCCIO_CPU1"
CDS_LOCATION"C7C7"
CDS_LIB"mstr_discrete"
PART_NUMBER"644066-127"
VALUE"100UF"
TOLERANCE"20%"
MATERIAL"X5R"
PACK_TYPE"1210"
VOLTAGE"16V"
LOCATION"C7C7";
"A"
$PN"1"17;
"B"
$PN"2"11;
%"GND"
"1","(825,1975)","0","mstr_symbols","I55";
;
HDL_POWER"GND"
BODY_TYPE"PLUMBING"
SIZE"1B"
CDS_LIB"mstr_symbols"
VOLTAGE"0.0V"
ROOM"PVCCIO_CPU1"
BOM_COST"MEM_VRD_PVCCIO_CPU1";
"A\NAC"11;
%"INDUCTOR"
"1","(325,2450)","0","mstr_discrete","I56";
;
CDS_SEC"1"
CDS_LIB"mstr_discrete"
ROOM"PVCCIO_CPU1"
CDS_LOCATION"L7C1"
SEC"1"
BOM_COST"PROC_VRD_VCCIO_CPU1"
SEC_TYPE"SM"
PACK_TYPE"SM"
MATERIAL"IND"
VALUE"100NH"
LOCATION"L7C1"
PART_NUMBER"D92183-020";
"INA\NAC"
$PN"1"12;
"INB\NAC"
$PN"2"17;
%"P12V_STBY"
"1","(-50,2550)","0","mstr_symbols","I57";
;
HDL_POWER"P12V_STBY"
BODY_TYPE"PLUMBING"
VOLTAGE"12.0V"
CDS_LIB"mstr_symbols"
SIZE"1B";
"G\NAC"12;
%"P5V_STBY"
"1","(-425,4700)","0","mstr_symbols","I58";
;
HDL_POWER"P5V_STBY"
BODY_TYPE"PLUMBING"
SIZE"1B"
CDS_LIB"mstr_symbols"
VOLTAGE"5.0V";
"G\NAC"13;
%"CAP_A"
"1","(-1925,1675)","0","dev_discrete","I60";
;
CDS_SEC"1"
$SEC"1"
ROOM"PVCCIO_CPU0"
BOM_COST"PROC_VRD_PVCCIO_CPU0"
CDS_LOCATION"C3P1"
CDS_LIB"dev_discrete"
PART_NUMBER"A36096-030"
PACK_TYPE"0402V"
MATERIAL"EMPTY"
LOCATION"C3P1"
VOLTAGE"16V"
VALUE"0.1UF"
TOLERANCE"10%";
"B"
$PN"2"22;
"A"
$PN"1"23;
%"RES"
"1","(-725,1150)","0","mstr_discrete","I68";
;
CDS_SEC"1"
$SEC"1"
CDS_LIB"mstr_discrete"
ROOM"PVCCIO_CPU0"
BOM_COST"PROC_VRD_PVCCIO_CPU0"
CDS_LOCATION"R3N20"
PACK_TYPE"0402"
MATERIAL"CHIP"
VALUE"100.0"
WATTAGE"1/16W"
TOLERANCE"1%"
PART_NUMBER"G21796-017"
LOCATION"R3N20";
"B"
$PN"2"14;
"A"
$PN"1"25;
%"GND"
"1","(-450,925)","0","mstr_symbols","I69";
;
HDL_POWER"GND"
BODY_TYPE"PLUMBING"
ROOM"PVCCIO_CPU0"
BOM_COST"MEM_VRD_PVCCIO_CPU0"
CDS_LIB"mstr_symbols"
SIZE"1B"
VOLTAGE"0";
"A\NAC"14;
%"RES"
"1","(-725,2325)","0","mstr_discrete","I74";
;
$SEC"1"
CDS_SEC"1"
CDS_LIB"mstr_discrete"
LOCATION"R3N21"
ROOM"PVCCIO_CPU0"
CDS_LOCATION"R3N21"
BOM_COST"PROC_VRD_PVCCIO_CPU0"
CDS_LOCATION"R3N21"
PACK_TYPE"0402"
LOCATION"R3N21"
VALUE"100.0"
MATERIAL"CHIP"
WATTAGE"1/16W"
PART_NUMBER"G21796-017"
TOLERANCE"1%";
"B"
$PN"2"15;
"A"
$PN"1"26;
%"PVCCIO_CPU0"
"1","(-500,2525)","0","mstr_symbols","I75";
;
VOLTAGE"1.1V"
CDS_LIB"mstr_symbols"
BODY_TYPE"PLUMBING"
HDL_POWER"PVCCIO_CPU0";
"G\NAC"15;
%"CAP_A"
"1","(3225,3275)","0","dev_discrete","I77";
;
CDS_LOCATION"C7C10"
CDS_SEC"1"
SEC_TYPE"0603V"
SEC"1"
CDS_LIB"dev_discrete"
PART_NUMBER"E15431-004"
VALUE"22.0UF"
LOCATION"C7C10"
MATERIAL"X6S"
VOLTAGE"4V"
TOLERANCE"20%"
PACK_TYPE"0603V";
"B"
$PN"2"7;
"A"
$PN"1"6;
%"RES"
"2","(3600,3275)","0","mstr_discrete","I78";
;
CDS_SEC"1"
SEC"1"
SEC_TYPE"0402"
CDS_LOCATION"R7C3"
CDS_LIB"mstr_discrete"
PART_NUMBER"G21796-208"
VALUE"51.1"
LOCATION"R7C3"
WATTAGE"1/16W"
MATERIAL"CHIP"
PACK_TYPE"0402"
TOLERANCE"1.0%";
"A"
$PN"1"6;
"B"
$PN"2"7;
%"VCC_CORE"
"1","(-3150,4575)","0","mstr_symbols","I79";
;
CDS_LIB"mstr_symbols"
HDL_POWER"VR_FET_SW_P12V_STBY_PVCCIO_CPU0";
"A"16;
%"VCC_CORE"
"1","(1025,2550)","0","mstr_symbols","I80";
;
CDS_LIB"mstr_symbols"
HDL_POWER"VR_FET_SW_P12V_STBY_PVCCIO_CPU0";
"A"17;
%"PVCCIO_CPU0"
"1","(3375,2675)","0","mstr_symbols","I82";
;
HDL_POWER"PVCCIO_CPU0"
BODY_TYPE"PLUMBING"
CDS_LIB"mstr_symbols"
VOLTAGE"1.1V";
"G\NAC"18;
END.
